# T6G (Grand Teton) — schematic netlist excerpt (pin names and nets, part order shuffled) for the footprints in the layout excerpt that follows; sources: Cadence DE-HDL packaged netlist, KiCad conversion of 04192023_DAF0TMB3IC0_F0TG_MB_C_brd_V02_OCP.brd

C2263  Q_CAP  22UF 4V 20% X6S  pkg C0402  page 72 : A = PVDDCR_SOC_P1 ; B = GND
C2404  Q_CAP  22UF 4V 20% X6S  pkg C0402  page 73 : A = PVDDCR_CPU1_P1 ; B = GND

(kicad_pcb
	(version 20260206)
	(generator "pcbnew")
	(generator_version "10.0")
	(general
		(thickness 1.6)
		(legacy_teardrops no)
	)
	(paper "A4")
	(title_block
		(title "04192023_DAF0TMB3IC0_F0TG_MB_C_brd_V02_OCP.brd")
		(comment 1 "Grand Teton / footprints 6884-6885 of 8354")
	)
	(layers
		(0 "F.Cu" signal "TOP")
		(4 "In1.Cu" signal "GND")
		(6 "In2.Cu" signal "IN1")
		(8 "In3.Cu" signal "GND1")
		(10 "In4.Cu" signal "IN2")
		(12 "In5.Cu" signal "GND2")
		(14 "In6.Cu" signal "IN3")
		(16 "In7.Cu" signal "GND3")
		(18 "In8.Cu" signal "VCC")
		(20 "In9.Cu" signal "VCC1")
		(22 "In10.Cu" signal "GND4")
		(24 "In11.Cu" signal "IN4")
		(26 "In12.Cu" signal "GND5")
		(28 "In13.Cu" signal "IN5")
		(30 "In14.Cu" signal "GND6")
		(32 "In15.Cu" signal "IN6")
		(34 "In16.Cu" signal "GND7")
		(2 "B.Cu" signal "BOTTOM")
		(9 "F.Adhes" user "F.Adhesive")
		(11 "B.Adhes" user "B.Adhesive")
		(13 "F.Paste" user "Package Geometry/Pastemask Top")
		(15 "B.Paste" user "Package Geometry/Pastemask Bottom")
		(5 "F.SilkS" user "Ref Des/Silkscreen Top")
		(7 "B.SilkS" user "Ref Des/Silkscreen Bottom")
		(1 "F.Mask" user "Board Geometry/Soldermask Top")
		(3 "B.Mask" user "Board Geometry/Soldermask Bottom")
		(17 "Dwgs.User" user "User.Drawings")
		(19 "Cmts.User" user "User.Comments")
		(21 "Eco1.User" user "User.Eco1")
		(23 "Eco2.User" user "User.Eco2")
		(25 "Edge.Cuts" user "Board Geometry/Outline")
		(27 "Margin" user)
		(31 "F.CrtYd" user "Package Geometry/Place Bound Top")
		(29 "B.CrtYd" user "Package Geometry/Place Bound Bottom")
		(35 "F.Fab" user "Ref Des/Assembly Top")
		(33 "B.Fab" user "Ref Des/Assembly Bottom")
	)
	(footprint ""
		(layer "B.Cu")
		(at 109.575854 -256.012442 -90)
		(property "Reference" "C2263"
			(at 0 0 90)
			(layer "B.SilkS")
			(hide yes)
			(effects
				(font
					(size 1.27 1.27)
				)
				(justify mirror)
			)
		)
		(property "Value" ""
			(at 0 0 90)
			(layer "B.Fab")
			(effects
				(font
					(size 1.27 1.27)
				)
				(justify mirror)
			)
		)
		(duplicate_pad_numbers_are_jumpers no)
		(fp_line
			(start -0.7874 0.4064)
			(end 0.7874 0.4064)
			(stroke
				(width 0.1524)
				(type default)
			)
			(layer "B.SilkS")
		)
		(fp_line
			(start 0.7874 0.4064)
			(end 0.7874 -0.4064)
			(stroke
				(width 0.1524)
				(type default)
			)
			(layer "B.SilkS")
		)
		(fp_line
			(start -0.7874 -0.4064)
			(end -0.7874 0.4064)
			(stroke
				(width 0.1524)
				(type default)
			)
			(layer "B.SilkS")
		)
		(fp_line
			(start 0.7874 -0.4064)
			(end -0.7874 -0.4064)
			(stroke
				(width 0.1524)
				(type default)
			)
			(layer "B.SilkS")
		)
		(fp_line
			(start -0.67945 0.3048)
			(end -0.120396 0.3048)
			(stroke
				(width 0.1)
				(type default)
			)
			(layer "B.Fab")
		)
		(fp_line
			(start -0.120396 0.3048)
			(end -0.120396 0.2794)
			(stroke
				(width 0.1)
				(type default)
			)
			(layer "B.Fab")
		)
		(fp_line
			(start 0.12065 0.3048)
			(end 0.67945 0.3048)
			(stroke
				(width 0.1)
				(type default)
			)
			(layer "B.Fab")
		)
		(fp_line
			(start 0.67945 0.3048)
			(end 0.67945 -0.305054)
			(stroke
				(width 0.1)
				(type default)
			)
			(layer "B.Fab")
		)
		(fp_line
			(start -0.120396 0.2794)
			(end 0.12065 0.2794)
			(stroke
				(width 0.1)
				(type default)
			)
			(layer "B.Fab")
		)
		(fp_line
			(start 0.12065 0.2794)
			(end 0.12065 0.3048)
			(stroke
				(width 0.1)
				(type default)
			)
			(layer "B.Fab")
		)
		(fp_line
			(start -0.12065 -0.2794)
			(end -0.12065 -0.3048)
			(stroke
				(width 0.1)
				(type default)
			)
			(layer "B.Fab")
		)
		(fp_line
			(start 0.12065 -0.2794)
			(end -0.12065 -0.2794)
			(stroke
				(width 0.1)
				(type default)
			)
			(layer "B.Fab")
		)
		(fp_line
			(start -0.67945 -0.3048)
			(end -0.67945 0.3048)
			(stroke
				(width 0.1)
				(type default)
			)
			(layer "B.Fab")
		)
		(fp_line
			(start -0.12065 -0.3048)
			(end -0.67945 -0.3048)
			(stroke
				(width 0.1)
				(type default)
			)
			(layer "B.Fab")
		)
		(fp_line
			(start 0.12065 -0.305054)
			(end 0.12065 -0.2794)
			(stroke
				(width 0.1)
				(type default)
			)
			(layer "B.Fab")
		)
		(fp_line
			(start 0.67945 -0.305054)
			(end 0.12065 -0.305054)
			(stroke
				(width 0.1)
				(type default)
			)
			(layer "B.Fab")
		)
		(pad "1" smd circle
			(at 0.40005 0 90)
			(size 0 0)
			(layers "B.Cu" "B.Mask" "B.Paste")
			(net "PVDDCR_SOC_P1")
		)
		(pad "2" smd circle
			(at -0.40005 0 90)
			(size 0 0)
			(layers "B.Cu" "B.Mask" "B.Paste")
			(net "GND")
		)
	)
	(footprint ""
		(layer "B.Cu")
		(at 109.768386 -268.418564)
		(property "Reference" "C2404"
			(at 0 0 0)
			(layer "B.SilkS")
			(hide yes)
			(effects
				(font
					(size 1.27 1.27)
				)
				(justify mirror)
			)
		)
		(property "Value" ""
			(at 0 0 0)
			(layer "B.Fab")
			(effects
				(font
					(size 1.27 1.27)
				)
				(justify mirror)
			)
		)
		(duplicate_pad_numbers_are_jumpers no)
		(fp_line
			(start -0.7874 -0.4064)
			(end -0.7874 0.4064)
			(stroke
				(width 0.1524)
				(type default)
			)
			(layer "B.SilkS")
		)
		(fp_line
			(start -0.7874 0.4064)
			(end 0.7874 0.4064)
			(stroke
				(width 0.1524)
				(type default)
			)
			(layer "B.SilkS")
		)
		(fp_line
			(start 0.7874 -0.4064)
			(end -0.7874 -0.4064)
			(stroke
				(width 0.1524)
				(type default)
			)
			(layer "B.SilkS")
		)
		(fp_line
			(start 0.7874 0.4064)
			(end 0.7874 -0.4064)
			(stroke
				(width 0.1524)
				(type default)
			)
			(layer "B.SilkS")
		)
		(fp_line
			(start -0.67945 -0.3048)
			(end -0.67945 0.3048)
			(stroke
				(width 0.1)
				(type default)
			)
			(layer "B.Fab")
		)
		(fp_line
			(start -0.67945 0.3048)
			(end -0.120396 0.3048)
			(stroke
				(width 0.1)
				(type default)
			)
			(layer "B.Fab")
		)
		(fp_line
			(start -0.12065 -0.3048)
			(end -0.67945 -0.3048)
			(stroke
				(width 0.1)
				(type default)
			)
			(layer "B.Fab")
		)
		(fp_line
			(start -0.12065 -0.2794)
			(end -0.12065 -0.3048)
			(stroke
				(width 0.1)
				(type default)
			)
			(layer "B.Fab")
		)
		(fp_line
			(start -0.120396 0.2794)
			(end 0.12065 0.2794)
			(stroke
				(width 0.1)
				(type default)
			)
			(layer "B.Fab")
		)
		(fp_line
			(start -0.120396 0.3048)
			(end -0.120396 0.2794)
			(stroke
				(width 0.1)
				(type default)
			)
			(layer "B.Fab")
		)
		(fp_line
			(start 0.12065 -0.305054)
			(end 0.12065 -0.2794)
			(stroke
				(width 0.1)
				(type default)
			)
			(layer "B.Fab")
		)
		(fp_line
			(start 0.12065 -0.2794)
			(end -0.12065 -0.2794)
			(stroke
				(width 0.1)
				(type default)
			)
			(layer "B.Fab")
		)
		(fp_line
			(start 0.12065 0.2794)
			(end 0.12065 0.3048)
			(stroke
				(width 0.1)
				(type default)
			)
			(layer "B.Fab")
		)
		(fp_line
			(start 0.12065 0.3048)
			(end 0.67945 0.3048)
			(stroke
				(width 0.1)
				(type default)
			)
			(layer "B.Fab")
		)
		(fp_line
			(start 0.67945 -0.305054)
			(end 0.12065 -0.305054)
			(stroke
				(width 0.1)
				(type default)
			)
			(layer "B.Fab")
		)
		(fp_line
			(start 0.67945 0.3048)
			(end 0.67945 -0.305054)
			(stroke
				(width 0.1)
				(type default)
			)
			(layer "B.Fab")
		)
		(pad "1" smd circle
			(at 0.40005 0 180)
			(size 0 0)
			(layers "B.Cu" "B.Mask" "B.Paste")
			(net "PVDDCR_CPU1_P1")
		)
		(pad "2" smd circle
			(at -0.40005 0 180)
			(size 0 0)
			(layers "B.Cu" "B.Mask" "B.Paste")
			(net "GND")
		)
	)
)
